FILE_TYPE = MACRO_DRAWING;
SET COLOR_WIRE YELLOW;
SET COLOR_PROP ORANGE;
SET COLOR_DOT WHITE;
SET COLOR_ARC YELLOW;
SET COLOR_BODY GREEN;
SET COLOR_NOTE PURPLE;
SET PROP_DISPLAY VALUE;
SET PAGE_NUMBER P231;
FORCEADD M24128BWMN6TP..1
(100 2250);
FORCEPROP 1 LAST PART_NUMBER AKE30Z00613
J 0
(-50 2475);
DISPLAY 0.723404 (-50 2475);
PAINT GREEN (-50 2475);
DISPLAY INVISIBLE (-50 2475);
FORCEPROP 1 LAST MATERIAL IC
J 0
(-54 2391);
DISPLAY 0.723404 (-54 2391);
PAINT GREEN (-54 2391);
FORCEPROP 2 LAST VALUE M24128-BWMN6TP
J 0
(-75 2700);
DISPLAY 0.638298 (-75 2700);
FORCEPROP 2 LAST PART_TYPE SMLF
J 0
(-75 2775);
DISPLAY 0.638298 (-75 2775);
FORCEPROP 1 LAST $LOCATION U64
J 0
(-75 2575);
DISPLAY 0.723404 (-75 2575);
PAINT GREEN (-75 2575);
FORCEPROP 0 LASTPIN (400 2325) $PN 1
J 0
(410 2335);
DISPLAY 0.680851 (410 2335);
PAINT MONO (410 2335);
FORCEPROP 0 LASTPIN (400 2275) $PN 2
J 0
(410 2285);
DISPLAY 0.680851 (410 2285);
PAINT MONO (410 2285);
FORCEPROP 0 LASTPIN (400 2225) $PN 3
J 0
(410 2235);
DISPLAY 0.680851 (410 2235);
PAINT MONO (410 2235);
FORCEPROP 0 LASTPIN (-200 2225) $PN 6
J 2
(-210 2235);
DISPLAY 0.680851 (-210 2235);
PAINT MONO (-210 2235);
FORCEPROP 0 LASTPIN (-200 2175) $PN 5
J 2
(-210 2185);
DISPLAY 0.680851 (-210 2185);
PAINT MONO (-210 2185);
FORCEPROP 0 LASTPIN (-200 2325) $PN 8
J 2
(-210 2335);
DISPLAY 0.680851 (-210 2335);
PAINT MONO (-210 2335);
FORCEPROP 0 LASTPIN (400 2175) $PN 4
J 0
(410 2185);
DISPLAY 0.680851 (410 2185);
PAINT MONO (410 2185);
FORCEPROP 0 LASTPIN (-200 2275) $PN 7
J 2
(-210 2285);
DISPLAY 0.680851 (-210 2285);
PAINT MONO (-210 2285);
FORCEPROP 1 LAST CDS_LMAN_SYM_OUTLINE -150,125,150,-125
J 0
(100 2250);
DISPLAY 0.468085 (100 2250);
PAINT GREEN (100 2250);
DISPLAY INVISIBLE (100 2250);
FORCEPROP 1 LAST NEEDS_NO_SIZE TRUE
J 0
(100 2250);
DISPLAY 0.723404 (100 2250);
PAINT GREEN (100 2250);
DISPLAY INVISIBLE (100 2250);
FORCEPROP 2 LAST CDS_LIB pure_quanta
J 2
(100 2250);
DISPLAY INVISIBLE (100 2250);
FORCEPROP 1 LAST PATH I35
J 0
(100 2250);
DISPLAY 0.723404 (100 2250);
PAINT GREEN (100 2250);
DISPLAY INVISIBLE (100 2250);
FORCEPROP 2 LAST CDS_LOCATION U64
J 0
(-50 2625);
DISPLAY 1.021277 (-50 2625);
DISPLAY INVISIBLE (-50 2625);
FORCEPROP 0 LAST $SEC 1
J 2
(-75 2825);
DISPLAY 0.680851 (-75 2825);
PAINT MONO (-75 2825);
DISPLAY INVISIBLE (-75 2825);
FORCEPROP 2 LAST CDS_SEC 1
J 0
(-50 2625);
DISPLAY 1.021277 (-50 2625);
DISPLAY INVISIBLE (-50 2625);
FORCEADD OFFPAGE..3
R 2
(-1800 2175);
FORCEPROP 2 LAST $XR0 231 
J 0
(-2080 2175);
DISPLAY 0.638298 (-2080 2175);
PAINT MONO (-2080 2175);
FORCEPROP 2 LAST CDS_LIB standard
J 0
(-1800 2175);
PAINT MONO (-1800 2175);
DISPLAY INVISIBLE (-1800 2175);
FORCEPROP 1 LAST OFFPAGE TRUE
J 2
(-2125 2050);
DISPLAY 0.872340 (-2125 2050);
DISPLAY INVISIBLE (-2125 2050);
FORCEPROP 1 LAST COMMENT_BODY TRUE
J 2
(-1750 2075);
DISPLAY 0.872340 (-1750 2075);
PAINT GREEN (-1750 2075);
DISPLAY INVISIBLE (-1750 2075);
FORCEPROP 2 LAST PATH I40
J 0
(-2125 2225);
DISPLAY 1.021277 (-2125 2225);
DISPLAY INVISIBLE (-2125 2225);
FORCEADD OFFPAGE..1
(-1800 2225);
FORCEPROP 2 LAST $XR0 231 
J 0
(-2052 2225);
DISPLAY 0.638298 (-2052 2225);
PAINT MONO (-2052 2225);
FORCEPROP 2 LAST CDS_LIB standard
J 0
(-1800 2225);
PAINT MONO (-1800 2225);
DISPLAY INVISIBLE (-1800 2225);
FORCEPROP 1 LAST OFFPAGE TRUE
J 0
(-1475 2100);
DISPLAY 0.872340 (-1475 2100);
PAINT GREEN (-1475 2100);
DISPLAY INVISIBLE (-1475 2100);
FORCEPROP 1 LAST COMMENT_BODY TRUE
J 0
(-1675 2125);
DISPLAY 0.872340 (-1675 2125);
PAINT GREEN (-1675 2125);
DISPLAY INVISIBLE (-1675 2125);
FORCEPROP 2 LAST PATH I41
J 0
(-1750 2300);
DISPLAY 1.021277 (-1750 2300);
DISPLAY INVISIBLE (-1750 2300);
FORCEADD Q_RES..2
(2125 2550);
FORCEPROP 1 LAST PART_NUMBER CS31002FB08
J 0
(2165 2425);
DISPLAY 0.510638 (2165 2425);
DISPLAY INVISIBLE (2165 2425);
FORCEPROP 1 LAST PACK_TYPE 0402LF
J 0
(2165 2425);
DISPLAY 0.638298 (2165 2425);
FORCEPROP 1 LAST MATERIAL EMPTY
J 0
(2165 2475);
DISPLAY 0.638298 (2165 2475);
PAINT RED (2165 2475);
FORCEPROP 1 LAST WATTAGE 1/16W
J 0
(2165 2525);
DISPLAY 0.638298 (2165 2525);
FORCEPROP 1 LAST VALUE 10K
J 0
(2170 2625);
DISPLAY 0.638298 (2170 2625);
FORCEPROP 1 LAST TOLERANCE 1%
J 0
(2170 2575);
DISPLAY 0.638298 (2170 2575);
FORCEPROP 1 LAST $LOCATION R717
J 0
(2170 2675);
DISPLAY 0.978723 (2170 2675);
FORCEPROP 1 LASTPIN (2125 2650) $PN 1
J 0
(2130 2612);
DISPLAY 0.787234 (2130 2612);
FORCEPROP 1 LASTPIN (2125 2450) $PN 2
J 0
(2130 2460);
DISPLAY 0.787234 (2130 2460);
FORCEPROP 2 LAST CDS_LIB pure_quanta
J 0
(2125 2550);
PAINT MONO (2125 2550);
DISPLAY INVISIBLE (2125 2550);
FORCEPROP 1 LAST PATH I45
J 0
(2175 2725);
DISPLAY 0.978723 (2175 2725);
PAINT WHITE (2175 2725);
DISPLAY INVISIBLE (2175 2725);
FORCEPROP 2 LAST CDS_LOCATION R717
J 0
(2175 2775);
DISPLAY 1.021277 (2175 2775);
DISPLAY INVISIBLE (2175 2775);
FORCEPROP 2 LAST $SEC 1
J 0
(2175 2775);
DISPLAY 0.680851 (2175 2775);
PAINT MONO (2175 2775);
DISPLAY INVISIBLE (2175 2775);
FORCEPROP 2 LAST CDS_SEC 1
J 0
(2175 2775);
DISPLAY 1.021277 (2175 2775);
DISPLAY INVISIBLE (2175 2775);
FORCEADD Q_RES..2
(1850 2550);
FORCEPROP 1 LAST PART_NUMBER CS31002FB08
J 0
(1890 2425);
DISPLAY 0.510638 (1890 2425);
DISPLAY INVISIBLE (1890 2425);
FORCEPROP 1 LAST WATTAGE 1/16W
J 0
(1890 2525);
DISPLAY 0.638298 (1890 2525);
FORCEPROP 1 LAST PACK_TYPE 0402LF
J 0
(1890 2425);
DISPLAY 0.638298 (1890 2425);
FORCEPROP 1 LAST VALUE 10K
J 0
(1895 2625);
DISPLAY 0.638298 (1895 2625);
FORCEPROP 1 LAST TOLERANCE 1%
J 0
(1895 2575);
DISPLAY 0.638298 (1895 2575);
FORCEPROP 1 LAST MATERIAL EMPTY
J 0
(1890 2475);
DISPLAY 0.638298 (1890 2475);
PAINT RED (1890 2475);
FORCEPROP 1 LAST $LOCATION R713
J 0
(1895 2675);
DISPLAY 0.978723 (1895 2675);
FORCEPROP 1 LASTPIN (1850 2650) $PN 1
J 0
(1855 2612);
DISPLAY 0.787234 (1855 2612);
FORCEPROP 1 LASTPIN (1850 2450) $PN 2
J 0
(1855 2460);
DISPLAY 0.787234 (1855 2460);
FORCEPROP 2 LAST CDS_LIB pure_quanta
J 0
(1850 2550);
PAINT MONO (1850 2550);
DISPLAY INVISIBLE (1850 2550);
FORCEPROP 1 LAST PATH I47
J 0
(1900 2725);
DISPLAY 0.978723 (1900 2725);
PAINT WHITE (1900 2725);
DISPLAY INVISIBLE (1900 2725);
FORCEPROP 2 LAST CDS_LOCATION R713
J 0
(1900 2775);
DISPLAY 1.021277 (1900 2775);
DISPLAY INVISIBLE (1900 2775);
FORCEPROP 2 LAST $SEC 1
J 0
(1900 2775);
DISPLAY 0.680851 (1900 2775);
PAINT MONO (1900 2775);
DISPLAY INVISIBLE (1900 2775);
FORCEPROP 2 LAST CDS_SEC 1
J 0
(1900 2775);
DISPLAY 1.021277 (1900 2775);
DISPLAY INVISIBLE (1900 2775);
FORCEADD UNIVERSAL_GND..1
(2400 1775);
FORCEPROP 3 LASTPIN (2400 1825) SIG_NAME GND\g
J 0
(2410 1835);
DISPLAY 0.659574 (2410 1835);
PAINT MONO (2410 1835);
DISPLAY INVISIBLE (2410 1835);
FORCEPROP 2 LAST CDS_LIB logical_power
J 0
(2400 1775);
PAINT MONO (2400 1775);
DISPLAY INVISIBLE (2400 1775);
FORCEPROP 1 LAST HDL_POWER GND
J 1
(2425 1700);
DISPLAY 0.872340 (2425 1700);
PAINT GREEN (2425 1700);
DISPLAY INVISIBLE (2425 1700);
FORCEPROP 1 LAST PATH I49
J 0
(2475 1775);
DISPLAY 0.872340 (2475 1775);
PAINT AQUA (2475 1775);
DISPLAY INVISIBLE (2475 1775);
FORCEPROP 2 LAST ROOM IO_SLOT
J 1
(2175 1850);
DISPLAY 0.744681 (2175 1850);
DISPLAY INVISIBLE (2175 1850);
FORCEADD Q_RES..2
(2125 2000);
FORCEPROP 1 LAST PART_NUMBER CS21002FB06
J 0
(2165 1875);
DISPLAY 0.510638 (2165 1875);
DISPLAY INVISIBLE (2165 1875);
FORCEPROP 1 LAST WATTAGE 1/16W
J 0
(2165 1975);
DISPLAY 0.638298 (2165 1975);
FORCEPROP 1 LAST MATERIAL CHIP
J 0
(2165 1925);
DISPLAY 0.638298 (2165 1925);
FORCEPROP 1 LAST VALUE 1K
J 0
(2170 2075);
DISPLAY 0.638298 (2170 2075);
FORCEPROP 1 LAST TOLERANCE 1%
J 0
(2170 2025);
DISPLAY 0.638298 (2170 2025);
FORCEPROP 1 LAST PACK_TYPE 0402LF
J 0
(2165 1875);
DISPLAY 0.638298 (2165 1875);
FORCEPROP 1 LAST $LOCATION R718
J 0
(2170 2125);
DISPLAY 0.978723 (2170 2125);
FORCEPROP 1 LASTPIN (2125 2100) $PN 1
J 0
(2130 2062);
DISPLAY 0.787234 (2130 2062);
FORCEPROP 1 LASTPIN (2125 1900) $PN 2
J 0
(2130 1910);
DISPLAY 0.787234 (2130 1910);
FORCEPROP 2 LAST CDS_LIB pure_quanta
J 0
(2125 2000);
PAINT MONO (2125 2000);
DISPLAY INVISIBLE (2125 2000);
FORCEPROP 1 LAST PATH I50
J 0
(2175 2175);
DISPLAY 0.978723 (2175 2175);
PAINT WHITE (2175 2175);
DISPLAY INVISIBLE (2175 2175);
FORCEPROP 2 LAST CDS_LOCATION R718
J 0
(2175 2225);
DISPLAY 1.021277 (2175 2225);
DISPLAY INVISIBLE (2175 2225);
FORCEPROP 2 LAST $SEC 1
J 0
(2175 2225);
DISPLAY 0.680851 (2175 2225);
PAINT MONO (2175 2225);
DISPLAY INVISIBLE (2175 2225);
FORCEPROP 2 LAST CDS_SEC 1
J 0
(2175 2225);
DISPLAY 1.021277 (2175 2225);
DISPLAY INVISIBLE (2175 2225);
FORCEADD UNIVERSAL_GND..1
(2125 1775);
FORCEPROP 3 LASTPIN (2125 1825) SIG_NAME GND\g
J 0
(2135 1835);
DISPLAY 0.659574 (2135 1835);
PAINT MONO (2135 1835);
DISPLAY INVISIBLE (2135 1835);
FORCEPROP 2 LAST CDS_LIB logical_power
J 0
(2125 1775);
PAINT MONO (2125 1775);
DISPLAY INVISIBLE (2125 1775);
FORCEPROP 1 LAST HDL_POWER GND
J 1
(2150 1700);
DISPLAY 0.872340 (2150 1700);
PAINT GREEN (2150 1700);
DISPLAY INVISIBLE (2150 1700);
FORCEPROP 1 LAST PATH I51
J 0
(2200 1775);
DISPLAY 0.872340 (2200 1775);
PAINT AQUA (2200 1775);
DISPLAY INVISIBLE (2200 1775);
FORCEPROP 2 LAST ROOM IO_SLOT
J 1
(1900 1850);
DISPLAY 0.744681 (1900 1850);
DISPLAY INVISIBLE (1900 1850);
FORCEADD Q_RES..2
(1850 2000);
FORCEPROP 1 LAST PART_NUMBER CS21002FB06
J 0
(1890 1875);
DISPLAY 0.510638 (1890 1875);
DISPLAY INVISIBLE (1890 1875);
FORCEPROP 1 LAST VALUE 1K
J 0
(1895 2075);
DISPLAY 0.638298 (1895 2075);
FORCEPROP 1 LAST PACK_TYPE 0402LF
J 0
(1890 1875);
DISPLAY 0.638298 (1890 1875);
FORCEPROP 1 LAST MATERIAL CHIP
J 0
(1890 1925);
DISPLAY 0.638298 (1890 1925);
FORCEPROP 1 LAST WATTAGE 1/16W
J 0
(1890 1975);
DISPLAY 0.638298 (1890 1975);
FORCEPROP 1 LAST TOLERANCE 1%
J 0
(1895 2025);
DISPLAY 0.638298 (1895 2025);
FORCEPROP 1 LAST $LOCATION R714
J 0
(1895 2125);
DISPLAY 0.978723 (1895 2125);
FORCEPROP 1 LASTPIN (1850 2100) $PN 1
J 0
(1855 2062);
DISPLAY 0.787234 (1855 2062);
FORCEPROP 1 LASTPIN (1850 1900) $PN 2
J 0
(1855 1910);
DISPLAY 0.787234 (1855 1910);
FORCEPROP 2 LAST CDS_LIB pure_quanta
J 0
(1850 2000);
PAINT MONO (1850 2000);
DISPLAY INVISIBLE (1850 2000);
FORCEPROP 1 LAST PATH I52
J 0
(1900 2175);
DISPLAY 0.978723 (1900 2175);
PAINT WHITE (1900 2175);
DISPLAY INVISIBLE (1900 2175);
FORCEPROP 2 LAST CDS_LOCATION R714
J 0
(1900 2225);
DISPLAY 1.021277 (1900 2225);
DISPLAY INVISIBLE (1900 2225);
FORCEPROP 2 LAST $SEC 1
J 0
(1900 2225);
DISPLAY 0.680851 (1900 2225);
PAINT MONO (1900 2225);
DISPLAY INVISIBLE (1900 2225);
FORCEPROP 2 LAST CDS_SEC 1
J 0
(1900 2225);
DISPLAY 1.021277 (1900 2225);
DISPLAY INVISIBLE (1900 2225);
FORCEADD UNIVERSAL_GND..1
(1850 1775);
FORCEPROP 3 LASTPIN (1850 1825) SIG_NAME GND\g
J 0
(1860 1835);
DISPLAY 0.659574 (1860 1835);
PAINT MONO (1860 1835);
DISPLAY INVISIBLE (1860 1835);
FORCEPROP 2 LAST CDS_LIB logical_power
J 0
(1850 1775);
PAINT MONO (1850 1775);
DISPLAY INVISIBLE (1850 1775);
FORCEPROP 1 LAST HDL_POWER GND
J 1
(1875 1700);
DISPLAY 0.872340 (1875 1700);
PAINT GREEN (1875 1700);
DISPLAY INVISIBLE (1875 1700);
FORCEPROP 1 LAST PATH I53
J 0
(1925 1775);
DISPLAY 0.872340 (1925 1775);
PAINT AQUA (1925 1775);
DISPLAY INVISIBLE (1925 1775);
FORCEPROP 2 LAST ROOM IO_SLOT
J 1
(1625 1850);
DISPLAY 0.744681 (1625 1850);
DISPLAY INVISIBLE (1625 1850);
FORCEADD UNIVERSAL_POWER..1
(-425 2900);
FORCEPROP 3 LASTPIN (-425 2850) SIG_NAME P3V3_AUX\g
J 0
(-415 2860);
DISPLAY 0.659574 (-415 2860);
PAINT MONO (-415 2860);
DISPLAY INVISIBLE (-415 2860);
FORCEPROP 1 LAST HDL_POWER P3V3_AUX
J 1
(-425 2950);
DISPLAY 0.872340 (-425 2950);
PAINT GREEN (-425 2950);
FORCEPROP 2 LAST CDS_LIB logical_power
J 0
(-425 2900);
PAINT MONO (-425 2900);
DISPLAY INVISIBLE (-425 2900);
FORCEPROP 1 LAST PATH I54
J 0
(-375 2925);
DISPLAY 0.872340 (-375 2925);
PAINT AQUA (-375 2925);
DISPLAY INVISIBLE (-375 2925);
FORCEADD Q_CAP..1
R 2
(-425 2575);
FORCEPROP 1 LAST PART_NUMBER CH4104K1B00
J 2
(-475 2425);
DISPLAY 0.510638 (-475 2425);
DISPLAY INVISIBLE (-475 2425);
FORCEPROP 1 LAST MATERIAL X7R
J 2
(-475 2475);
DISPLAY 0.510638 (-475 2475);
FORCEPROP 1 LAST TOLERANCE 10%
J 2
(-475 2525);
DISPLAY 0.510638 (-475 2525);
FORCEPROP 1 LAST VOLTAGE 25V
J 2
(-475 2575);
DISPLAY 0.510638 (-475 2575);
FORCEPROP 1 LAST VALUE 0.1UF
J 2
(-475 2625);
DISPLAY 0.510638 (-475 2625);
FORCEPROP 1 LAST PACK_TYPE 0402
J 2
(-475 2375);
DISPLAY 0.510638 (-475 2375);
FORCEPROP 1 LAST $LOCATION C629
J 2
(-475 2675);
DISPLAY 0.978723 (-475 2675);
FORCEPROP 1 LASTPIN (-425 2675) $PN 1
J 2
(-435 2655);
DISPLAY 0.787234 (-435 2655);
FORCEPROP 1 LASTPIN (-425 2475) $PN 2
J 2
(-435 2455);
DISPLAY 0.787234 (-435 2455);
FORCEPROP 2 LAST CDS_LIB pure_quanta
J 0
(-425 2575);
PAINT MONO (-425 2575);
DISPLAY INVISIBLE (-425 2575);
FORCEPROP 1 LAST PATH I55
J 2
(-475 2725);
DISPLAY 0.978723 (-475 2725);
PAINT WHITE (-475 2725);
DISPLAY INVISIBLE (-475 2725);
FORCEPROP 2 LAST CDS_LOCATION C629
J 0
(-475 2775);
DISPLAY 1.021277 (-475 2775);
DISPLAY INVISIBLE (-475 2775);
FORCEPROP 2 LAST $SEC 1
J 0
(-475 2775);
DISPLAY 0.680851 (-475 2775);
PAINT MONO (-475 2775);
DISPLAY INVISIBLE (-475 2775);
FORCEPROP 2 LAST CDS_SEC 1
J 0
(-475 2775);
DISPLAY 1.021277 (-475 2775);
DISPLAY INVISIBLE (-475 2775);
FORCEADD UNIVERSAL_GND..1
(-425 2350);
FORCEPROP 3 LASTPIN (-425 2400) SIG_NAME GND\g
J 0
(-415 2410);
DISPLAY 0.659574 (-415 2410);
PAINT MONO (-415 2410);
DISPLAY INVISIBLE (-415 2410);
FORCEPROP 2 LAST CDS_LIB logical_power
J 0
(-425 2350);
PAINT MONO (-425 2350);
DISPLAY INVISIBLE (-425 2350);
FORCEPROP 1 LAST HDL_POWER GND
J 1
(-400 2275);
DISPLAY 0.872340 (-400 2275);
PAINT GREEN (-400 2275);
DISPLAY INVISIBLE (-400 2275);
FORCEPROP 1 LAST PATH I56
J 0
(-350 2350);
DISPLAY 0.872340 (-350 2350);
PAINT AQUA (-350 2350);
DISPLAY INVISIBLE (-350 2350);
FORCEADD Q_RES..2
(-975 1950);
FORCEPROP 1 LAST PART_NUMBER CS21002FB06
J 0
(-935 1825);
DISPLAY 0.510638 (-935 1825);
DISPLAY INVISIBLE (-935 1825);
FORCEPROP 1 LAST MATERIAL CHIP
J 0
(-935 1875);
DISPLAY 0.510638 (-935 1875);
FORCEPROP 1 LAST VALUE 1K
J 0
(-930 2025);
DISPLAY 0.510638 (-930 2025);
FORCEPROP 1 LAST WATTAGE 1/16W
J 0
(-935 1925);
DISPLAY 0.510638 (-935 1925);
FORCEPROP 1 LAST TOLERANCE 1%
J 0
(-930 1975);
DISPLAY 0.510638 (-930 1975);
FORCEPROP 1 LAST PACK_TYPE 0402LF
J 0
(-935 1775);
DISPLAY 0.510638 (-935 1775);
FORCEPROP 1 LAST $LOCATION R710
J 0
(-930 2075);
DISPLAY 0.978723 (-930 2075);
FORCEPROP 1 LASTPIN (-975 2050) $PN 1
J 0
(-970 2012);
DISPLAY 0.787234 (-970 2012);
FORCEPROP 1 LASTPIN (-975 1850) $PN 2
J 0
(-970 1860);
DISPLAY 0.787234 (-970 1860);
FORCEPROP 2 LAST CDS_LIB pure_quanta
J 0
(-975 1950);
PAINT MONO (-975 1950);
DISPLAY INVISIBLE (-975 1950);
FORCEPROP 1 LAST PATH I57
J 0
(-925 2125);
DISPLAY 0.978723 (-925 2125);
PAINT WHITE (-925 2125);
DISPLAY INVISIBLE (-925 2125);
FORCEPROP 2 LAST CDS_LOCATION R710
J 0
(-925 2175);
DISPLAY 1.021277 (-925 2175);
DISPLAY INVISIBLE (-925 2175);
FORCEPROP 2 LAST $SEC 1
J 0
(-925 2175);
DISPLAY 0.680851 (-925 2175);
PAINT MONO (-925 2175);
DISPLAY INVISIBLE (-925 2175);
FORCEPROP 2 LAST CDS_SEC 1
J 0
(-925 2175);
DISPLAY 1.021277 (-925 2175);
DISPLAY INVISIBLE (-925 2175);
FORCEADD UNIVERSAL_GND..1
(-975 1725);
FORCEPROP 3 LASTPIN (-975 1775) SIG_NAME GND\g
J 0
(-965 1785);
DISPLAY 0.659574 (-965 1785);
PAINT MONO (-965 1785);
DISPLAY INVISIBLE (-965 1785);
FORCEPROP 2 LAST CDS_LIB logical_power
J 0
(-975 1725);
PAINT MONO (-975 1725);
DISPLAY INVISIBLE (-975 1725);
FORCEPROP 1 LAST HDL_POWER GND
J 1
(-950 1650);
DISPLAY 0.872340 (-950 1650);
PAINT GREEN (-950 1650);
DISPLAY INVISIBLE (-950 1650);
FORCEPROP 1 LAST PATH I58
J 0
(-900 1725);
DISPLAY 0.872340 (-900 1725);
PAINT AQUA (-900 1725);
DISPLAY INVISIBLE (-900 1725);
FORCEADD UNIVERSAL_GND..1
(550 1925);
FORCEPROP 3 LASTPIN (550 1975) SIG_NAME GND\g
J 0
(560 1985);
DISPLAY 0.659574 (560 1985);
PAINT MONO (560 1985);
DISPLAY INVISIBLE (560 1985);
FORCEPROP 2 LAST CDS_LIB logical_power
J 0
(550 1925);
PAINT MONO (550 1925);
DISPLAY INVISIBLE (550 1925);
FORCEPROP 1 LAST HDL_POWER GND
J 1
(575 1850);
DISPLAY 0.872340 (575 1850);
PAINT GREEN (575 1850);
DISPLAY INVISIBLE (575 1850);
FORCEPROP 1 LAST PATH I59
J 0
(625 1925);
DISPLAY 0.872340 (625 1925);
PAINT AQUA (625 1925);
DISPLAY INVISIBLE (625 1925);
FORCEADD UNIVERSAL_POWER..1
(1850 2925);
FORCEPROP 3 LASTPIN (1850 2875) SIG_NAME P3V3_AUX\g
J 0
(1860 2885);
DISPLAY 0.659574 (1860 2885);
PAINT MONO (1860 2885);
DISPLAY INVISIBLE (1860 2885);
FORCEPROP 1 LAST HDL_POWER P3V3_AUX
J 1
(1850 2975);
DISPLAY 0.872340 (1850 2975);
PAINT GREEN (1850 2975);
FORCEPROP 2 LAST CDS_LIB logical_power
J 0
(1850 2925);
PAINT MONO (1850 2925);
DISPLAY INVISIBLE (1850 2925);
FORCEPROP 1 LAST PATH I60
J 0
(1900 2950);
DISPLAY 0.872340 (1900 2950);
PAINT AQUA (1900 2950);
DISPLAY INVISIBLE (1900 2950);
FORCEADD Q_RES..2
(2400 2000);
FORCEPROP 1 LAST PART_NUMBER CS21002FB06
J 0
(2440 1825);
DISPLAY 0.638298 (2440 1825);
DISPLAY INVISIBLE (2440 1825);
FORCEPROP 1 LAST TOLERANCE 1%
J 0
(2445 2025);
DISPLAY 0.638298 (2445 2025);
FORCEPROP 1 LAST VALUE 1K
J 0
(2445 2075);
DISPLAY 0.638298 (2445 2075);
FORCEPROP 1 LAST PACK_TYPE 0402LF
J 0
(2440 1875);
DISPLAY 0.638298 (2440 1875);
FORCEPROP 1 LAST MATERIAL EMPTY
J 0
(2440 1925);
DISPLAY 0.638298 (2440 1925);
PAINT RED (2440 1925);
FORCEPROP 1 LAST WATTAGE 1/16W
J 0
(2440 1975);
DISPLAY 0.638298 (2440 1975);
FORCEPROP 1 LAST $LOCATION R722
J 0
(2445 2125);
DISPLAY 0.978723 (2445 2125);
FORCEPROP 1 LASTPIN (2400 2100) $PN 1
J 0
(2405 2062);
DISPLAY 0.787234 (2405 2062);
FORCEPROP 1 LASTPIN (2400 1900) $PN 2
J 0
(2405 1910);
DISPLAY 0.787234 (2405 1910);
FORCEPROP 2 LAST CDS_LIB pure_quanta
J 0
(2400 2000);
PAINT MONO (2400 2000);
DISPLAY INVISIBLE (2400 2000);
FORCEPROP 1 LAST PATH I61
J 0
(2450 2175);
DISPLAY 0.978723 (2450 2175);
PAINT WHITE (2450 2175);
DISPLAY INVISIBLE (2450 2175);
FORCEPROP 2 LAST CDS_LOCATION R722
J 0
(2450 2225);
DISPLAY 1.021277 (2450 2225);
DISPLAY INVISIBLE (2450 2225);
FORCEPROP 2 LAST $SEC 1
J 0
(2450 2225);
DISPLAY 0.680851 (2450 2225);
PAINT MONO (2450 2225);
DISPLAY INVISIBLE (2450 2225);
FORCEPROP 2 LAST CDS_SEC 1
J 0
(2450 2225);
DISPLAY 1.021277 (2450 2225);
DISPLAY INVISIBLE (2450 2225);
FORCEADD Q_RES..2
(2400 2550);
FORCEPROP 1 LAST PART_NUMBER CS31002FB08
J 0
(2440 2375);
DISPLAY 0.638298 (2440 2375);
DISPLAY INVISIBLE (2440 2375);
FORCEPROP 1 LAST TOLERANCE 1%
J 0
(2445 2575);
DISPLAY 0.638298 (2445 2575);
FORCEPROP 1 LAST VALUE 10K
J 0
(2445 2625);
DISPLAY 0.638298 (2445 2625);
FORCEPROP 1 LAST WATTAGE 1/16W
J 0
(2440 2525);
DISPLAY 0.638298 (2440 2525);
FORCEPROP 1 LAST PACK_TYPE 0402LF
J 0
(2440 2425);
DISPLAY 0.638298 (2440 2425);
FORCEPROP 1 LAST MATERIAL CHIP
J 0
(2440 2475);
DISPLAY 0.638298 (2440 2475);
FORCEPROP 1 LAST $LOCATION R721
J 0
(2445 2675);
DISPLAY 0.978723 (2445 2675);
FORCEPROP 1 LASTPIN (2400 2650) $PN 1
J 0
(2405 2612);
DISPLAY 0.787234 (2405 2612);
FORCEPROP 1 LASTPIN (2400 2450) $PN 2
J 0
(2405 2460);
DISPLAY 0.787234 (2405 2460);
FORCEPROP 2 LAST CDS_LIB pure_quanta
J 0
(2400 2550);
PAINT MONO (2400 2550);
DISPLAY INVISIBLE (2400 2550);
FORCEPROP 1 LAST PATH I62
J 0
(2450 2725);
DISPLAY 0.978723 (2450 2725);
PAINT WHITE (2450 2725);
DISPLAY INVISIBLE (2450 2725);
FORCEPROP 2 LAST CDS_LOCATION R721
J 0
(2450 2775);
DISPLAY 1.021277 (2450 2775);
DISPLAY INVISIBLE (2450 2775);
FORCEPROP 2 LAST $SEC 1
J 0
(2450 2775);
DISPLAY 0.680851 (2450 2775);
PAINT MONO (2450 2775);
DISPLAY INVISIBLE (2450 2775);
FORCEPROP 2 LAST CDS_SEC 1
J 0
(2450 2775);
DISPLAY 1.021277 (2450 2775);
DISPLAY INVISIBLE (2450 2775);
FORCEADD Q_RES..2
(-1575 2525);
FORCEPROP 1 LAST PART_NUMBER CS24702JB10
J 0
(-1535 2400);
DISPLAY 0.638298 (-1535 2400);
DISPLAY INVISIBLE (-1535 2400);
FORCEPROP 1 LAST PACK_TYPE 0402LF
J 0
(-1535 2350);
DISPLAY 0.638298 (-1535 2350);
FORCEPROP 1 LAST TOLERANCE 5%
J 0
(-1530 2550);
DISPLAY 0.638298 (-1530 2550);
FORCEPROP 1 LAST MATERIAL EMPTY
J 0
(-1535 2450);
DISPLAY 0.638298 (-1535 2450);
PAINT RED (-1535 2450);
FORCEPROP 1 LAST WATTAGE 1/16W
J 0
(-1535 2500);
DISPLAY 0.638298 (-1535 2500);
FORCEPROP 1 LAST VALUE 4.7K
J 0
(-1530 2600);
DISPLAY 0.638298 (-1530 2600);
FORCEPROP 1 LAST $LOCATION R1332
J 0
(-1530 2650);
DISPLAY 0.787234 (-1530 2650);
FORCEPROP 1 LASTPIN (-1575 2625) $PN 1
J 0
(-1570 2587);
DISPLAY 0.787234 (-1570 2587);
FORCEPROP 1 LASTPIN (-1575 2425) $PN 2
J 0
(-1570 2435);
DISPLAY 0.787234 (-1570 2435);
FORCEPROP 2 LAST CDS_LIB pure_quanta
J 0
(-1575 2525);
PAINT MONO (-1575 2525);
DISPLAY INVISIBLE (-1575 2525);
FORCEPROP 1 LAST PATH I93
J 0
(-1525 2700);
DISPLAY 0.978723 (-1525 2700);
PAINT WHITE (-1525 2700);
DISPLAY INVISIBLE (-1525 2700);
FORCEPROP 2 LAST CDS_LOCATION R1332
J 0
(-1525 2750);
DISPLAY 1.021277 (-1525 2750);
DISPLAY INVISIBLE (-1525 2750);
FORCEPROP 2 LAST $SEC 1
J 0
(-1525 2750);
DISPLAY 0.680851 (-1525 2750);
PAINT MONO (-1525 2750);
DISPLAY INVISIBLE (-1525 2750);
FORCEPROP 2 LAST CDS_SEC 1
J 0
(-1525 2750);
DISPLAY 1.021277 (-1525 2750);
DISPLAY INVISIBLE (-1525 2750);
FORCEADD Q_RES..2
R 2
(-1675 2525);
FORCEPROP 1 LAST PART_NUMBER CS24702JB10
J 2
(-1715 2400);
DISPLAY 0.638298 (-1715 2400);
DISPLAY INVISIBLE (-1715 2400);
FORCEPROP 1 LAST TOLERANCE 5%
J 2
(-1720 2550);
DISPLAY 0.638298 (-1720 2550);
FORCEPROP 1 LAST WATTAGE 1/16W
J 2
(-1715 2500);
DISPLAY 0.638298 (-1715 2500);
FORCEPROP 1 LAST MATERIAL EMPTY
J 2
(-1715 2450);
DISPLAY 0.638298 (-1715 2450);
PAINT RED (-1715 2450);
FORCEPROP 1 LAST PACK_TYPE 0402LF
J 2
(-1715 2350);
DISPLAY 0.638298 (-1715 2350);
FORCEPROP 1 LAST VALUE 4.7K
J 2
(-1720 2600);
DISPLAY 0.638298 (-1720 2600);
FORCEPROP 1 LAST $LOCATION R1331
J 2
(-1720 2650);
DISPLAY 0.787234 (-1720 2650);
FORCEPROP 1 LASTPIN (-1675 2625) $PN 1
J 2
(-1680 2587);
DISPLAY 0.787234 (-1680 2587);
FORCEPROP 1 LASTPIN (-1675 2425) $PN 2
J 2
(-1680 2435);
DISPLAY 0.787234 (-1680 2435);
FORCEPROP 2 LAST CDS_LIB pure_quanta
J 2
(-1675 2525);
PAINT MONO (-1675 2525);
DISPLAY INVISIBLE (-1675 2525);
FORCEPROP 1 LAST PATH I95
J 2
(-1725 2700);
DISPLAY 0.978723 (-1725 2700);
PAINT WHITE (-1725 2700);
DISPLAY INVISIBLE (-1725 2700);
FORCEPROP 2 LAST CDS_LOCATION R1331
J 0
(-1725 2750);
DISPLAY 1.021277 (-1725 2750);
DISPLAY INVISIBLE (-1725 2750);
FORCEPROP 2 LAST $SEC 1
J 0
(-1725 2750);
DISPLAY 0.680851 (-1725 2750);
PAINT MONO (-1725 2750);
DISPLAY INVISIBLE (-1725 2750);
FORCEPROP 2 LAST CDS_SEC 1
J 0
(-1725 2750);
DISPLAY 1.021277 (-1725 2750);
DISPLAY INVISIBLE (-1725 2750);
FORCEADD UNIVERSAL_POWER..1
(-1675 2825);
FORCEPROP 3 LASTPIN (-1675 2775) SIG_NAME P3V3_AUX\g
J 0
(-1665 2785);
DISPLAY 0.659574 (-1665 2785);
PAINT MONO (-1665 2785);
DISPLAY INVISIBLE (-1665 2785);
FORCEPROP 1 LAST HDL_POWER P3V3_AUX
J 1
(-1675 2875);
DISPLAY 0.872340 (-1675 2875);
PAINT GREEN (-1675 2875);
FORCEPROP 2 LAST CDS_LIB logical_power
J 0
(-1675 2825);
PAINT MONO (-1675 2825);
DISPLAY INVISIBLE (-1675 2825);
FORCEPROP 1 LAST PATH I96
J 0
(-1625 2850);
DISPLAY 0.872340 (-1625 2850);
PAINT AQUA (-1625 2850);
DISPLAY INVISIBLE (-1625 2850);
FORCEADD QUANTA_TITLE_BLOCK_C..1
(4700 -1475);
FORCEPROP 0 LAST CDS_CON_LAST_MODIFIED Fri Aug 25 14:04:11 2023
J 0
(2815 -1460);
PAINT MONO (2815 -1460);
DISPLAY INVISIBLE (2815 -1460);
FORCEPROP 1 LAST CUSTOM_TXT_CDS <CON_LAST_MODIFIED>
J 0
(2815 -1460);
DISPLAY 0.978723 (2815 -1460);
FORCEPROP 2 LAST CUSTOM_TXT_CDS <XR_PAGE_TITLE>
J 0
(-3190 3775);
DISPLAY 0.638298 (-3190 3775);
PAINT PINK (-3190 3775);
DISPLAY INVISIBLE (-3190 3775);
FORCEPROP 1 LAST CUSTOM_TXT_CDS <NAME_2>
J 0
(1525 -1425);
FORCEPROP 1 LAST CUSTOM_TXT_CDS <NAME_1>
J 0
(1525 -1300);
FORCEPROP 1 LAST CUSTOM_TXT_CDS <Q_NUMBER>
J 0
(3297 -1372);
DISPLAY 1.212766 (3297 -1372);
FORCEPROP 1 LAST CUSTOM_TXT_CDS <Q_PROJ>
J 0
(2318 -1373);
DISPLAY 1.212766 (2318 -1373);
FORCEPROP 1 LAST CUSTOM_TXT_CDS <Q_REV>
J 0
(4516 -1372);
DISPLAY 1.212766 (4516 -1372);
FORCEPROP 1 LAST CUSTOM_TXT_CDS <CON_PAGE_NUM> OF <CON_TOTAL_PAGES>
J 0
(4254 -1457);
DISPLAY 0.978723 (4254 -1457);
FORCEPROP 1 LAST Q_TITLE MB FRU
J 0
(-4566 -1474);
DISPLAY 2.446809 (-4566 -1474);
PAINT GREEN (-4566 -1474);
FORCEPROP 1 LAST Q_DEPT 
J 1
(937 -1426);
DISPLAY 1.957447 (937 -1426);
PAINT GREEN (937 -1426);
FORCEPROP 2 LAST CDS_XR_PAGE_TITLE CR-243 : @S9S_MB_2U_LIB.S9S_MB_2U(SCH_1):PAGE243
J 0
(-3190 3775);
DISPLAY 0.638298 (-3190 3775);
PAINT PINK (-3190 3775);
DISPLAY INVISIBLE (-3190 3775);
FORCEPROP 1 LAST COMMENT_BODY TRUE
J 0
(4712 -1488);
DISPLAY 0.978723 (4712 -1488);
PAINT GREEN (4712 -1488);
DISPLAY INVISIBLE (4712 -1488);
FORCEPROP 2 LAST PAGE_BORDER TRUE
J 0
(-3190 3775);
DISPLAY 0.638298 (-3190 3775);
PAINT PINK (-3190 3775);
DISPLAY INVISIBLE (-3190 3775);
FORCEPROP 1 LAST CDS_LMAN_SYM_OUTLINE -9475,6775,100,-125
J 0
(4700 -1475);
DISPLAY 0.468085 (4700 -1475);
PAINT GREEN (4700 -1475);
DISPLAY INVISIBLE (4700 -1475);
FORCEPROP 2 LAST CDS_LIB pure_quanta
J 0
(4700 -1475);
PAINT MONO (4700 -1475);
DISPLAY INVISIBLE (4700 -1475);
FORCEADD DNS..2
(2400 1975);
PAINT RED (2400 1975);
FORCEPROP 2 LAST CDS_LIB mstr_misc
J 0
(2400 1975);
PAINT MONO (2400 1975);
DISPLAY INVISIBLE (2400 1975);
FORCEPROP 1 LAST COMMENT_BODY TRUE
J 0
(2400 1975);
DISPLAY INVISIBLE (2400 1975);
FORCEADD DNS..2
(2130 2520);
PAINT RED (2130 2520);
FORCEPROP 2 LAST CDS_LIB mstr_misc
J 0
(2130 2520);
PAINT MONO (2130 2520);
DISPLAY INVISIBLE (2130 2520);
FORCEPROP 1 LAST COMMENT_BODY TRUE
J 0
(2130 2520);
DISPLAY INVISIBLE (2130 2520);
FORCEADD DNS..2
(1855 2520);
PAINT RED (1855 2520);
FORCEPROP 2 LAST CDS_LIB mstr_misc
J 0
(1855 2520);
PAINT MONO (1855 2520);
DISPLAY INVISIBLE (1855 2520);
FORCEPROP 1 LAST COMMENT_BODY TRUE
J 0
(1855 2520);
DISPLAY INVISIBLE (1855 2520);
FORCEADD DNS..2
(-1575 2500);
PAINT RED (-1575 2500);
FORCEPROP 2 LAST CDS_LIB mstr_misc
J 0
(-1575 2500);
DISPLAY INVISIBLE (-1575 2500);
FORCEPROP 1 LAST COMMENT_BODY TRUE
J 0
(-1575 2500);
DISPLAY INVISIBLE (-1575 2500);
FORCEADD DNS..2
(-1675 2500);
PAINT RED (-1675 2500);
FORCEPROP 2 LAST CDS_LIB mstr_misc
J 0
(-1675 2500);
DISPLAY INVISIBLE (-1675 2500);
FORCEPROP 1 LAST COMMENT_BODY TRUE
J 0
(-1675 2500);
DISPLAY INVISIBLE (-1675 2500);
WIRE 16 -1 (1850 2800)(1850 2875);
WIRE 16 -1 (1850 2800)(2125 2800);
WIRE 16 -1 (1850 2650)(1850 2800);
WIRE 16 -1 (-425 2850)(-425 2775);
WIRE 16 -1 (-1675 2775)(-1675 2725);
WIRE 16 -1 (2400 1825)(2400 1900);
WIRE 16 -1 (2125 1825)(2125 1900);
WIRE 16 -1 (1850 1825)(1850 1900);
WIRE 16 -1 (550 1975)(550 2175);
WIRE 16 -1 (-425 2475)(-425 2400);
WIRE 16 -1 (-975 1850)(-975 1775);
WIRE 16 -1 (-975 2050)(-975 2275);
WIRE 16 -1 (-200 2275)(-975 2275);
FORCEPROP 2 LAST SIG_NAME PD_MB_FRU_WP
J 0
(-835 2285);
DISPLAY 0.510638 (-835 2285);
PAINT WHITE (-835 2285);
WIRE 16 -1 (-1750 2175)(-1575 2175);
FORCEPROP 0 LAST CDS_PHYS_NET_NAME SMB_PCIE_3V3AUX_SCL
J 0
(-1710 2223);
PAINT MONO (-1710 2223);
DISPLAY INVISIBLE (-1710 2223);
WIRE 16 -1 (-1575 2175)(-200 2175);
FORCEPROP 0 LAST CDS_PHYS_NET_NAME SMB_PCIE_3V3AUX_SDA_R
J 0
(-785 2223);
PAINT MONO (-785 2223);
DISPLAY INVISIBLE (-785 2223);
FORCEPROP 2 LAST SIG_NAME SMB_FRU_3V3AUX_SDA
J 0
(-1535 2185);
DISPLAY 0.510638 (-1535 2185);
PAINT WHITE (-1535 2185);
WIRE 16 -1 (-1575 2425)(-1575 2175);
WIRE 16 -1 (2400 2325)(400 2325);
FORCEPROP 0 LAST CDS_PHYS_NET_NAME PCA9548_PCIE_ADDR2
J 0
(1140 2373);
PAINT MONO (1140 2373);
DISPLAY INVISIBLE (1140 2373);
FORCEPROP 2 LAST SIG_NAME MB_FRU_ADDR0
J 0
(565 2335);
DISPLAY 0.808511 (565 2335);
PAINT WHITE (565 2335);
WIRE 16 -1 (2400 2100)(2400 2325);
WIRE 16 -1 (2400 2325)(2400 2450);
WIRE 16 -1 (400 2275)(2125 2275);
FORCEPROP 0 LAST CDS_PHYS_NET_NAME PCA9548_PCIE_ADDR2
J 0
(1140 2323);
PAINT MONO (1140 2323);
DISPLAY INVISIBLE (1140 2323);
FORCEPROP 2 LAST SIG_NAME MB_FRU_ADDR1
J 0
(565 2285);
DISPLAY 0.808511 (565 2285);
PAINT WHITE (565 2285);
WIRE 16 -1 (2125 2275)(2125 2450);
WIRE 16 -1 (2125 2100)(2125 2275);
WIRE 16 -1 (400 2225)(1850 2225);
FORCEPROP 0 LAST CDS_PHYS_NET_NAME PCA9548_PCIE_ADDR2
J 0
(1140 2273);
PAINT MONO (1140 2273);
DISPLAY INVISIBLE (1140 2273);
FORCEPROP 2 LAST SIG_NAME MB_FRU_ADDR2
J 0
(565 2235);
DISPLAY 0.808511 (565 2235);
PAINT WHITE (565 2235);
WIRE 16 -1 (1850 2225)(1850 2100);
WIRE 16 -1 (1850 2450)(1850 2225);
WIRE 16 -1 (400 2175)(550 2175);
WIRE 16 -1 (-1675 2425)(-1675 2225);
WIRE 16 -1 (-1675 2225)(-200 2225);
FORCEPROP 0 LAST CDS_PHYS_NET_NAME SMB_PCIE_3V3AUX_SCL_R
J 0
(-785 2273);
PAINT MONO (-785 2273);
DISPLAY INVISIBLE (-785 2273);
FORCEPROP 2 LAST SIG_NAME SMB_FRU_3V3AUX_SCL
J 0
(-1535 2235);
DISPLAY 0.510638 (-1535 2235);
PAINT WHITE (-1535 2235);
WIRE 16 -1 (-1750 2225)(-1675 2225);
FORCEPROP 0 LAST CDS_PHYS_NET_NAME SMB_PCIE_3V3AUX_SDA
J 0
(-1710 2273);
PAINT MONO (-1710 2273);
DISPLAY INVISIBLE (-1710 2273);
WIRE 16 -1 (2125 2650)(2125 2800);
WIRE 16 -1 (2125 2800)(2400 2800);
WIRE 16 -1 (2400 2650)(2400 2800);
WIRE 16 -1 (-300 2325)(-200 2325);
FORCEPROP 0 LAST VOLTAGE 3.3
J 0
(-250 2325);
PAINT MONO (-250 2325);
DISPLAY INVISIBLE (-250 2325);
FORCEPROP 0 LAST CDS_PHYS_NET_NAME P3V3_AUX
J 0
(-250 2372);
PAINT MONO (-250 2372);
DISPLAY INVISIBLE (-250 2372);
FORCEPROP 0 LAST $PHYS_NET_NAME P3V3_AUX
J 0
(-250 2419);
PAINT MONO (-250 2419);
DISPLAY INVISIBLE (-250 2419);
WIRE 16 -1 (-300 2325)(-300 2775);
FORCEPROP 0 LAST VOLTAGE 3.3
J 0
(-300 2550);
PAINT MONO (-300 2550);
DISPLAY INVISIBLE (-300 2550);
FORCEPROP 0 LAST CDS_PHYS_NET_NAME P3V3_AUX
J 0
(-300 2597);
PAINT MONO (-300 2597);
DISPLAY INVISIBLE (-300 2597);
FORCEPROP 0 LAST $PHYS_NET_NAME P3V3_AUX
J 0
(-300 2644);
PAINT MONO (-300 2644);
DISPLAY INVISIBLE (-300 2644);
WIRE 16 -1 (-425 2775)(-425 2675);
WIRE 16 -1 (-425 2775)(-300 2775);
FORCEPROP 0 LAST VOLTAGE 3.3
J 0
(-362 2775);
PAINT MONO (-362 2775);
DISPLAY INVISIBLE (-362 2775);
FORCEPROP 0 LAST CDS_PHYS_NET_NAME P3V3_AUX
J 0
(-362 2822);
PAINT MONO (-362 2822);
DISPLAY INVISIBLE (-362 2822);
FORCEPROP 0 LAST $PHYS_NET_NAME P3V3_AUX
J 0
(-362 2869);
PAINT MONO (-362 2869);
DISPLAY INVISIBLE (-362 2869);
WIRE 16 -1 (-1675 2725)(-1675 2625);
WIRE 16 -1 (-1575 2725)(-1675 2725);
WIRE 16 -1 (-1575 2625)(-1575 2725);
DOT 1 (-1675 2225);
DOT 1 (-1575 2175);
DOT 1 (-1675 2725);
DOT 1 (-425 2775);
DOT 1 (1850 2225);
DOT 1 (2125 2275);
DOT 1 (2400 2325);
DOT 1 (1850 2800);
DOT 1 (2125 2800);
FORCENOTE
20210603 MODIFY FOR GT
(-1625 3025) 0;
DISPLAY LEFT (-1625 3025);
DISPLAY 2.510638 (-1625 3025);
PAINT PINK (-1625 3025);
FORCENOTE
FRU ADDR: 0XA2
(-2550 1725) 0;
DISPLAY LEFT (-2550 1725);
DISPLAY 1.595745 (-2550 1725);
PAINT SKYBLUE (-2550 1725);
QUIT
